(kicad_pcb
	(version 20260206)
	(generator "pcbnew")
	(generator_version "10.0")
	(general
		(thickness 1.6)
		(legacy_teardrops no)
	)
	(paper "A4")
	(title_block
		(title "Bryce Canyon_F.DPB_16315-1-OCP.brd")
		(comment 1 "Bryce Canyon / footprints 1539-1544 of 2223")
	)
	(layers
		(0 "F.Cu" signal "TOP")
		(4 "In1.Cu" signal "L2GND")
		(6 "In2.Cu" signal "L3")
		(8 "In3.Cu" signal "L4GND")
		(10 "In4.Cu" signal "L5")
		(12 "In5.Cu" signal "L6VCC")
		(14 "In6.Cu" signal "L7VCC")
		(16 "In7.Cu" signal "L8")
		(18 "In8.Cu" signal "L9GND")
		(20 "In9.Cu" signal "L10")
		(22 "In10.Cu" signal "L11GND")
		(2 "B.Cu" signal "BOTTOM")
		(9 "F.Adhes" user "F.Adhesive")
		(11 "B.Adhes" user "B.Adhesive")
		(13 "F.Paste" user "Package Geometry/Pastemask Top")
		(15 "B.Paste" user "Package Geometry/Pastemask Bottom")
		(5 "F.SilkS" user "Ref Des/Silkscreen Top")
		(7 "B.SilkS" user "Ref Des/Silkscreen Bottom")
		(1 "F.Mask" user "Board Geometry/Soldermask Top")
		(3 "B.Mask" user "Board Geometry/Soldermask Bottom")
		(17 "Dwgs.User" user "User.Drawings")
		(19 "Cmts.User" user "User.Comments")
		(21 "Eco1.User" user "User.Eco1")
		(23 "Eco2.User" user "User.Eco2")
		(25 "Edge.Cuts" user "Board Geometry/Outline")
		(27 "Margin" user)
		(31 "F.CrtYd" user "Package Geometry/Place Bound Top")
		(29 "B.CrtYd" user "Package Geometry/Place Bound Bottom")
		(35 "F.Fab" user "Ref Des/Assembly Top")
		(33 "B.Fab" user "Ref Des/Assembly Bottom")
	)
	(footprint ""
		(layer "F.Cu")
		(at 364.798102 -42.585894 180)
		(property "Reference" "R851"
			(at 0 0 180)
			(layer "F.SilkS")
			(hide yes)
			(effects
				(font
					(size 1.27 1.27)
				)
			)
		)
		(property "Value" "1KR2F-3-GP"
			(at 0.064008 -3.993896 180)
			(unlocked yes)
			(layer "F.Fab")
			(hide yes)
			(effects
				(font
					(size 1.016 1.016)
					(thickness 0.1524)
				)
			)
		)
		(property "Device Type" "R402H16"
			(at 0.064008 -5.517896 180)
			(unlocked yes)
			(layer "F.Fab")
			(hide yes)
			(effects
				(font
					(size 1.016 1.016)
					(thickness 0.1524)
				)
			)
		)
		(duplicate_pad_numbers_are_jumpers no)
		(fp_line
			(start 0.508 -0.9398)
			(end -0.508 -0.9398)
			(stroke
				(width 0.1524)
				(type default)
			)
			(layer "F.SilkS")
		)
		(fp_line
			(start -0.508 -0.9398)
			(end -0.508 0.9398)
			(stroke
				(width 0.1524)
				(type default)
			)
			(layer "F.SilkS")
		)
		(fp_rect
			(start -0.508 0.9398)
			(end 0.508 -0.9398)
			(stroke
				(width 0)
				(type default)
			)
			(fill no)
			(layer "F.CrtYd")
		)
		(fp_rect
			(start -0.508 0.9398)
			(end 0.508 -0.9398)
			(stroke
				(width 0)
				(type default)
			)
			(fill no)
			(layer "F.Fab")
		)
		(pad "1" smd custom
			(at 0 -0.4445 180)
			(size 0.1397 0.1397)
			(layers "F.Cu" "F.Mask" "F.Paste")
			(net "P3V3_STBY_A")
			(options
				(clearance outline)
				(anchor circle)
			)
			(primitives
				(gr_poly
					(pts
						(arc
							(start -0.1778 -0.2794)
							(mid -0.249642 -0.249642)
							(end -0.2794 -0.1778)
						)
						(arc
							(start -0.2794 0.1778)
							(mid -0.249642 0.249642)
							(end -0.1778 0.2794)
						)
						(arc
							(start 0.1778 0.2794)
							(mid 0.249642 0.249642)
							(end 0.2794 0.1778)
						)
						(arc
							(start 0.2794 -0.1778)
							(mid 0.249642 -0.249642)
							(end 0.1778 -0.2794)
						)
					)
					(width 0)
					(fill yes)
				)
			)
		)
		(pad "2" smd custom
			(at 0 0.4445 180)
			(size 0.1397 0.1397)
			(layers "F.Cu" "F.Mask" "F.Paste")
			(net "SW_PWR_R_HDD31")
			(options
				(clearance outline)
				(anchor circle)
			)
			(primitives
				(gr_poly
					(pts
						(arc
							(start -0.1778 -0.2794)
							(mid -0.249642 -0.249642)
							(end -0.2794 -0.1778)
						)
						(arc
							(start -0.2794 0.1778)
							(mid -0.249642 0.249642)
							(end -0.1778 0.2794)
						)
						(arc
							(start 0.1778 0.2794)
							(mid 0.249642 0.249642)
							(end 0.2794 0.1778)
						)
						(arc
							(start 0.2794 -0.1778)
							(mid 0.249642 -0.249642)
							(end 0.1778 -0.2794)
						)
					)
					(width 0)
					(fill yes)
				)
			)
		)
	)
	(footprint ""
		(layer "F.Cu")
		(at 146.884898 -170.285918 180)
		(property "Reference" "Q96"
			(at 0 0 180)
			(layer "F.SilkS")
			(hide yes)
			(effects
				(font
					(size 1.27 1.27)
				)
			)
		)
		(property "Value" "AO4406AL-GP"
			(at -3.707384 -1.5367 180)
			(unlocked yes)
			(layer "F.Fab")
			(hide yes)
			(effects
				(font
					(size 1.016 1.016)
					(thickness 0.1524)
				)
			)
		)
		(property "Device Type" "SOIC8H69"
			(at -3.707384 -3.0607 180)
			(unlocked yes)
			(layer "F.Fab")
			(hide yes)
			(effects
				(font
					(size 1.016 1.016)
					(thickness 0.1524)
				)
			)
		)
		(duplicate_pad_numbers_are_jumpers no)
		(fp_line
			(start 2.1336 1.4224)
			(end 2.1336 -1.4224)
			(stroke
				(width 0.1524)
				(type default)
			)
			(layer "F.SilkS")
		)
		(fp_line
			(start 2.1336 -1.4224)
			(end -2.7432 -1.4224)
			(stroke
				(width 0.1524)
				(type default)
			)
			(layer "F.SilkS")
		)
		(fp_line
			(start -2.1844 -0.0508)
			(end -2.7178 0.508)
			(stroke
				(width 0.1524)
				(type default)
			)
			(layer "F.SilkS")
		)
		(fp_line
			(start -2.6289 3.4417)
			(end -2.6289 1.4732)
			(stroke
				(width 0.381)
				(type default)
			)
			(layer "F.SilkS")
		)
		(fp_line
			(start -2.7178 -0.508)
			(end -2.1844 -0.0508)
			(stroke
				(width 0.1524)
				(type default)
			)
			(layer "F.SilkS")
		)
		(fp_line
			(start -2.7432 1.4224)
			(end 2.1336 1.4224)
			(stroke
				(width 0.1524)
				(type default)
			)
			(layer "F.SilkS")
		)
		(fp_line
			(start -2.7432 1.4224)
			(end -2.6416 1.4224)
			(stroke
				(width 0.1524)
				(type default)
			)
			(layer "F.SilkS")
		)
		(fp_line
			(start -2.7432 -1.4224)
			(end -2.7432 1.4224)
			(stroke
				(width 0.1524)
				(type default)
			)
			(layer "F.SilkS")
		)
		(fp_poly
			(pts
				(xy -2.2098 -1.4224) (xy -2.2098 1.4224) (xy 2.2098 1.4224) (xy 2.2098 -1.4224)
			)
			(stroke
				(width 0)
				(type default)
			)
			(fill yes)
			(layer "F.SilkS")
		)
		(fp_rect
			(start -2.450084 2.999994)
			(end 2.450084 -2.999994)
			(stroke
				(width 0)
				(type default)
			)
			(fill no)
			(layer "F.CrtYd")
		)
		(fp_poly
			(pts
				(xy -2.8194 3.6322) (xy -2.8194 -3.6322) (xy 2.8194 -3.6322) (xy 2.8194 1.18364) (xy 2.450084 1.18364)
				(xy 2.450084 -2.999994) (xy -2.450084 -2.999994) (xy -2.450084 2.999994) (xy 2.450084 2.999994)
				(xy 2.450084 1.18618) (xy 2.8194 1.18618) (xy 2.8194 3.6322)
			)
			(stroke
				(width 0)
				(type default)
			)
			(fill no)
			(layer "F.CrtYd")
		)
		(fp_rect
			(start -2.8194 3.6322)
			(end 2.8194 -3.6322)
			(stroke
				(width 0)
				(type default)
			)
			(fill no)
			(layer "F.Fab")
		)
		(pad "1" smd rect
			(at -1.905 2.54 180)
			(size 0.635 1.651)
			(layers "F.Cu" "F.Mask" "F.Paste")
			(net "P5V_HDD16")
		)
		(pad "2" smd rect
			(at -0.635 2.54 180)
			(size 0.635 1.651)
			(layers "F.Cu" "F.Mask" "F.Paste")
			(net "P5V_HDD16")
		)
		(pad "3" smd rect
			(at 0.635 2.54 180)
			(size 0.635 1.651)
			(layers "F.Cu" "F.Mask" "F.Paste")
			(net "P5V_HDD16")
		)
		(pad "4" smd rect
			(at 1.905 2.54 180)
			(size 0.635 1.651)
			(layers "F.Cu" "F.Mask" "F.Paste")
			(net "SW_HDD_P16")
		)
		(pad "5" smd rect
			(at 1.905 -2.54 180)
			(size 0.635 1.651)
			(layers "F.Cu" "F.Mask" "F.Paste")
			(net "P5V_A_2")
		)
		(pad "6" smd rect
			(at 0.635 -2.54 180)
			(size 0.635 1.651)
			(layers "F.Cu" "F.Mask" "F.Paste")
			(net "P5V_A_2")
		)
		(pad "7" smd rect
			(at -0.635 -2.54 180)
			(size 0.635 1.651)
			(layers "F.Cu" "F.Mask" "F.Paste")
			(net "P5V_A_2")
		)
		(pad "8" smd rect
			(at -1.905 -2.54 180)
			(size 0.635 1.651)
			(layers "F.Cu" "F.Mask" "F.Paste")
			(net "P5V_A_2")
		)
	)
	(footprint ""
		(layer "F.Cu")
		(at 317.60414 -59.616086 180)
		(property "Reference" "R393"
			(at 0 0 180)
			(layer "F.SilkS")
			(hide yes)
			(effects
				(font
					(size 1.27 1.27)
				)
			)
		)
		(property "Value" "10KR2F-2-GP"
			(at 0.064008 -3.993896 180)
			(unlocked yes)
			(layer "F.Fab")
			(hide yes)
			(effects
				(font
					(size 1.016 1.016)
					(thickness 0.1524)
				)
			)
		)
		(property "Device Type" "R402H16"
			(at 0.064008 -5.517896 180)
			(unlocked yes)
			(layer "F.Fab")
			(hide yes)
			(effects
				(font
					(size 1.016 1.016)
					(thickness 0.1524)
				)
			)
		)
		(duplicate_pad_numbers_are_jumpers no)
		(fp_line
			(start 0.508 -0.9398)
			(end -0.508 -0.9398)
			(stroke
				(width 0.1524)
				(type default)
			)
			(layer "F.SilkS")
		)
		(fp_line
			(start -0.508 -0.9398)
			(end -0.508 0.9398)
			(stroke
				(width 0.1524)
				(type default)
			)
			(layer "F.SilkS")
		)
		(fp_rect
			(start -0.508 0.9398)
			(end 0.508 -0.9398)
			(stroke
				(width 0)
				(type default)
			)
			(fill no)
			(layer "F.CrtYd")
		)
		(fp_rect
			(start -0.508 0.9398)
			(end 0.508 -0.9398)
			(stroke
				(width 0)
				(type default)
			)
			(fill no)
			(layer "F.Fab")
		)
		(pad "1" smd custom
			(at 0 -0.4445 180)
			(size 0.1397 0.1397)
			(layers "F.Cu" "F.Mask" "F.Paste")
			(net "SYS_B_RESET_N")
			(options
				(clearance outline)
				(anchor circle)
			)
			(primitives
				(gr_poly
					(pts
						(arc
							(start -0.1778 -0.2794)
							(mid -0.249642 -0.249642)
							(end -0.2794 -0.1778)
						)
						(arc
							(start -0.2794 0.1778)
							(mid -0.249642 0.249642)
							(end -0.1778 0.2794)
						)
						(arc
							(start 0.1778 0.2794)
							(mid 0.249642 0.249642)
							(end 0.2794 0.1778)
						)
						(arc
							(start 0.2794 -0.1778)
							(mid 0.249642 -0.249642)
							(end 0.1778 -0.2794)
						)
					)
					(width 0)
					(fill yes)
				)
			)
		)
		(pad "2" smd custom
			(at 0 0.4445 180)
			(size 0.1397 0.1397)
			(layers "F.Cu" "F.Mask" "F.Paste")
			(net "GND")
			(options
				(clearance outline)
				(anchor circle)
			)
			(primitives
				(gr_poly
					(pts
						(arc
							(start -0.1778 -0.2794)
							(mid -0.249642 -0.249642)
							(end -0.2794 -0.1778)
						)
						(arc
							(start -0.2794 0.1778)
							(mid -0.249642 0.249642)
							(end -0.1778 0.2794)
						)
						(arc
							(start 0.1778 0.2794)
							(mid 0.249642 0.249642)
							(end 0.2794 0.1778)
						)
						(arc
							(start 0.2794 -0.1778)
							(mid 0.249642 -0.249642)
							(end 0.1778 -0.2794)
						)
					)
					(width 0)
					(fill yes)
				)
			)
		)
	)
	(footprint ""
		(layer "F.Cu")
		(at 109.895386 -130.261614 -90)
		(property "Reference" "R517"
			(at 0 0 270)
			(layer "F.SilkS")
			(hide yes)
			(effects
				(font
					(size 1.27 1.27)
				)
			)
		)
		(property "Value" "4K7R2J-2-GP"
			(at 0.064008 -3.993896 270)
			(unlocked yes)
			(layer "F.Fab")
			(hide yes)
			(effects
				(font
					(size 1.016 1.016)
					(thickness 0.1524)
				)
			)
		)
		(property "Device Type" "R402H16"
			(at 0.064008 -5.517896 270)
			(unlocked yes)
			(layer "F.Fab")
			(hide yes)
			(effects
				(font
					(size 1.016 1.016)
					(thickness 0.1524)
				)
			)
		)
		(duplicate_pad_numbers_are_jumpers no)
		(fp_line
			(start -0.508 -0.9398)
			(end -0.508 0.9398)
			(stroke
				(width 0.1524)
				(type default)
			)
			(layer "F.SilkS")
		)
		(fp_line
			(start 0.508 -0.9398)
			(end -0.508 -0.9398)
			(stroke
				(width 0.1524)
				(type default)
			)
			(layer "F.SilkS")
		)
		(fp_rect
			(start -0.508 0.9398)
			(end 0.508 -0.9398)
			(stroke
				(width 0)
				(type default)
			)
			(fill no)
			(layer "F.CrtYd")
		)
		(fp_rect
			(start -0.508 0.9398)
			(end 0.508 -0.9398)
			(stroke
				(width 0)
				(type default)
			)
			(fill no)
			(layer "F.Fab")
		)
		(pad "1" smd custom
			(at 0 -0.4445 270)
			(size 0.1397 0.1397)
			(layers "F.Cu" "F.Mask" "F.Paste")
			(net "DRIVE_A_15_FLT_LED")
			(options
				(clearance outline)
				(anchor circle)
			)
			(primitives
				(gr_poly
					(pts
						(arc
							(start -0.1778 -0.2794)
							(mid -0.249642 -0.249642)
							(end -0.2794 -0.1778)
						)
						(arc
							(start -0.2794 0.1778)
							(mid -0.249642 0.249642)
							(end -0.1778 0.2794)
						)
						(arc
							(start 0.1778 0.2794)
							(mid 0.249642 0.249642)
							(end 0.2794 0.1778)
						)
						(arc
							(start 0.2794 -0.1778)
							(mid 0.249642 -0.249642)
							(end 0.1778 -0.2794)
						)
					)
					(width 0)
					(fill yes)
				)
			)
		)
		(pad "2" smd custom
			(at 0 0.4445 270)
			(size 0.1397 0.1397)
			(layers "F.Cu" "F.Mask" "F.Paste")
			(net "GND")
			(options
				(clearance outline)
				(anchor circle)
			)
			(primitives
				(gr_poly
					(pts
						(arc
							(start -0.1778 -0.2794)
							(mid -0.249642 -0.249642)
							(end -0.2794 -0.1778)
						)
						(arc
							(start -0.2794 0.1778)
							(mid -0.249642 0.249642)
							(end -0.1778 0.2794)
						)
						(arc
							(start 0.1778 0.2794)
							(mid 0.249642 0.249642)
							(end 0.2794 0.1778)
						)
						(arc
							(start 0.2794 -0.1778)
							(mid 0.249642 -0.249642)
							(end 0.1778 -0.2794)
						)
					)
					(width 0)
					(fill yes)
				)
			)
		)
	)
	(footprint ""
		(layer "F.Cu")
		(at 238.099346 -228.96703 180)
		(property "Reference" "Q15"
			(at 0 0 180)
			(layer "F.SilkS")
			(hide yes)
			(effects
				(font
					(size 1.27 1.27)
				)
			)
		)
		(property "Value" "SSM3K324R-GP"
			(at 0.127 -8.9662 180)
			(unlocked yes)
			(layer "F.Fab")
			(hide yes)
			(effects
				(font
					(size 1.016 1.016)
					(thickness 0.1524)
				)
			)
		)
		(property "Device Type" "SOT23DGS2D4H35"
			(at 0.127 -10.4902 180)
			(unlocked yes)
			(layer "F.Fab")
			(hide yes)
			(effects
				(font
					(size 1.016 1.016)
					(thickness 0.1524)
				)
			)
		)
		(duplicate_pad_numbers_are_jumpers no)
		(fp_line
			(start 1.651 1.778)
			(end 1.651 -1.778)
			(stroke
				(width 0.1524)
				(type default)
			)
			(layer "F.SilkS")
		)
		(fp_line
			(start 1.651 -1.778)
			(end -1.651 -1.778)
			(stroke
				(width 0.1524)
				(type default)
			)
			(layer "F.SilkS")
		)
		(fp_line
			(start -1.651 1.778)
			(end 1.651 1.778)
			(stroke
				(width 0.1524)
				(type default)
			)
			(layer "F.SilkS")
		)
		(fp_line
			(start -1.651 -1.778)
			(end -1.651 1.778)
			(stroke
				(width 0.1524)
				(type default)
			)
			(layer "F.SilkS")
		)
		(fp_poly
			(pts
				(xy -1.778 1.8796) (xy -1.778 -1.8796) (xy 1.778 -1.8796) (xy 1.778 1.8796)
			)
			(stroke
				(width 0)
				(type default)
			)
			(fill no)
			(layer "F.CrtYd")
		)
		(fp_poly
			(pts
				(xy -1.778 1.8796) (xy -1.778 -1.8796) (xy 1.778 -1.8796) (xy 1.778 1.8796)
			)
			(stroke
				(width 0)
				(type default)
			)
			(fill no)
			(layer "F.Fab")
		)
		(pad "D" smd custom
			(at 0 -0.9525 180)
			(size 0.1905 0.1905)
			(layers "F.Cu" "F.Mask" "F.Paste")
			(net "P3V3_STBY_A")
			(options
				(clearance outline)
				(anchor circle)
			)
			(primitives
				(gr_poly
					(pts
						(arc
							(start -0.1778 0.5715)
							(mid -0.321484 0.511984)
							(end -0.381 0.3683)
						)
						(arc
							(start -0.381 -0.3683)
							(mid -0.321484 -0.511984)
							(end -0.1778 -0.5715)
						)
						(arc
							(start 0.1778 -0.5715)
							(mid 0.321484 -0.511984)
							(end 0.381 -0.3683)
						)
						(arc
							(start 0.381 0.3683)
							(mid 0.321484 0.511984)
							(end 0.1778 0.5715)
						)
					)
					(width 0)
					(fill yes)
				)
			)
		)
		(pad "G" smd custom
			(at -0.98425 0.9525 180)
			(size 0.1905 0.1905)
			(layers "F.Cu" "F.Mask" "F.Paste")
			(net "SCC_FULL_PWR_EN_5V")
			(options
				(clearance outline)
				(anchor circle)
			)
			(primitives
				(gr_poly
					(pts
						(arc
							(start -0.1778 0.5715)
							(mid -0.321484 0.511984)
							(end -0.381 0.3683)
						)
						(arc
							(start -0.381 -0.3683)
							(mid -0.321484 -0.511984)
							(end -0.1778 -0.5715)
						)
						(arc
							(start 0.1778 -0.5715)
							(mid 0.321484 -0.511984)
							(end 0.381 -0.3683)
						)
						(arc
							(start 0.381 0.3683)
							(mid 0.321484 0.511984)
							(end 0.1778 0.5715)
						)
					)
					(width 0)
					(fill yes)
				)
			)
		)
		(pad "S" smd custom
			(at 0.98425 0.9525 180)
			(size 0.1905 0.1905)
			(layers "F.Cu" "F.Mask" "F.Paste")
			(net "GPIO_VCC_U7")
			(options
				(clearance outline)
				(anchor circle)
			)
			(primitives
				(gr_poly
					(pts
						(arc
							(start -0.1778 0.5715)
							(mid -0.321484 0.511984)
							(end -0.381 0.3683)
						)
						(arc
							(start -0.381 -0.3683)
							(mid -0.321484 -0.511984)
							(end -0.1778 -0.5715)
						)
						(arc
							(start 0.1778 -0.5715)
							(mid 0.321484 -0.511984)
							(end 0.381 -0.3683)
						)
						(arc
							(start 0.381 0.3683)
							(mid 0.321484 0.511984)
							(end 0.1778 0.5715)
						)
					)
					(width 0)
					(fill yes)
				)
			)
		)
	)
	(footprint ""
		(layer "F.Cu")
		(at 20.430998 -278.554942 180)
		(property "Reference" "Q217"
			(at 0 0 180)
			(layer "F.SilkS")
			(hide yes)
			(effects
				(font
					(size 1.27 1.27)
				)
			)
		)
		(property "Value" "2N7002KDW-GP"
			(at -2.3622 -8.2042 180)
			(unlocked yes)
			(layer "F.Fab")
			(hide yes)
			(effects
				(font
					(size 1.016 1.016)
					(thickness 0.1524)
				)
			)
		)
		(property "Device Type" "SOT-363H44"
			(at -2.3622 -10.1092 180)
			(unlocked yes)
			(layer "F.Fab")
			(hide yes)
			(effects
				(font
					(size 1.016 1.016)
					(thickness 0.1524)
				)
			)
		)
		(duplicate_pad_numbers_are_jumpers no)
		(fp_line
			(start 1.4478 1.7018)
			(end 1.4478 -1.7018)
			(stroke
				(width 0.1524)
				(type default)
			)
			(layer "F.SilkS")
		)
		(fp_line
			(start 1.4478 -1.7018)
			(end -1.4478 -1.7018)
			(stroke
				(width 0.1524)
				(type default)
			)
			(layer "F.SilkS")
		)
		(fp_line
			(start -1.27 1.524)
			(end -1.27 0.6604)
			(stroke
				(width 0.4826)
				(type default)
			)
			(layer "F.SilkS")
		)
		(fp_line
			(start -1.4478 1.7018)
			(end 1.4478 1.7018)
			(stroke
				(width 0.1524)
				(type default)
			)
			(layer "F.SilkS")
		)
		(fp_line
			(start -1.4478 -1.7018)
			(end -1.4478 1.7018)
			(stroke
				(width 0.1524)
				(type default)
			)
			(layer "F.SilkS")
		)
		(fp_poly
			(pts
				(xy -1.524 -1.778) (xy 1.524 -1.778) (xy 1.524 1.778) (xy -1.524 1.778)
			)
			(stroke
				(width 0)
				(type default)
			)
			(fill no)
			(layer "F.CrtYd")
		)
		(fp_poly
			(pts
				(xy -1.524 -1.778) (xy 1.524 -1.778) (xy 1.524 1.778) (xy -1.524 1.778)
			)
			(stroke
				(width 0)
				(type default)
			)
			(fill no)
			(layer "F.Fab")
		)
		(pad "1" smd rect
			(at -0.65024 0.9398 180)
			(size 0.4064 1.016)
			(layers "F.Cu" "F.Mask" "F.Paste")
			(net "GND")
		)
		(pad "2" smd rect
			(at 0 0.9398 180)
			(size 0.4064 1.016)
			(layers "F.Cu" "F.Mask" "F.Paste")
			(net "SW_PWR_R_HDD0")
		)
		(pad "3" smd rect
			(at 0.65024 0.9398 180)
			(size 0.4064 1.016)
			(layers "F.Cu" "F.Mask" "F.Paste")
			(net "SW_HDD_P0")
		)
		(pad "4" smd rect
			(at 0.65024 -0.9398 180)
			(size 0.4064 1.016)
			(layers "F.Cu" "F.Mask" "F.Paste")
			(net "GND")
		)
		(pad "5" smd rect
			(at 0 -0.9398 180)
			(size 0.4064 1.016)
			(layers "F.Cu" "F.Mask" "F.Paste")
			(net "SW_HDD_G0")
		)
		(pad "6" smd rect
			(at -0.65024 -0.9398 180)
			(size 0.4064 1.016)
			(layers "F.Cu" "F.Mask" "F.Paste")
			(net "SW_HDD_R0")
		)
	)
)
